# T6G (Grand Teton) — schematic netlist excerpt (pin names and nets, part order shuffled) for the footprints in the layout excerpt that follows; sources: Cadence DE-HDL packaged netlist, KiCad conversion of 04192023_DAF0TMB3IC0_F0TG_MB_C_brd_V02_OCP.brd

PU206  RS31312R  IC  pkg QFN22_TH_3X5  page 141
  EN  = P12V_OCP_V3_2_EN_2_R3
  LOADEN  = GND
  ENTM  = GND
  TIMER  = P12V_OCP_TIMER_2
  ISET  = P12V_OCP_ISET_2
  SS  = P12V_OCP_SS_2
  GND  = GND
  IMON  = P12V_OCP_IMON_2
  FLTB  = P12V_OCP_FLTB_2
  PG  = HP_LVC3_OCP_V3_2_P12V_PWRGD
  OV  = P12V_OCP_OV_FB_2
  AVIN  = P12V_OCP_AVIN_PD_2
  VOUT_13  = P12V_OCP_V3_2
  VOUT_14  = P12V_OCP_V3_2
  VOUT_15  = P12V_OCP_V3_2
  VOUT_16  = P12V_OCP_V3_2
  VOUT_17  = P12V_OCP_V3_2
  VOUT_18  = P12V_OCP_V3_2
  VOUT_19  = P12V_OCP_V3_2
  VOUT_20  = P12V_OCP_V3_2
  VIN_21_22  = P12V_AUX
  VIN_23  = P12V_AUX
  VIN_24  = P12V_AUX
  VIN_25  = P12V_AUX
  VIN_26  = P12V_AUX

(kicad_pcb
	(version 20260206)
	(generator "pcbnew")
	(generator_version "10.0")
	(general
		(thickness 1.6)
		(legacy_teardrops no)
	)
	(paper "A4")
	(title_block
		(title "04192023_DAF0TMB3IC0_F0TG_MB_C_brd_V02_OCP.brd")
		(comment 1 "Grand Teton / footprint 3421 of 8354 (PU206), pads 1-25 of 25")
	)
	(layers
		(0 "F.Cu" signal "TOP")
		(4 "In1.Cu" signal "GND")
		(6 "In2.Cu" signal "IN1")
		(8 "In3.Cu" signal "GND1")
		(10 "In4.Cu" signal "IN2")
		(12 "In5.Cu" signal "GND2")
		(14 "In6.Cu" signal "IN3")
		(16 "In7.Cu" signal "GND3")
		(18 "In8.Cu" signal "VCC")
		(20 "In9.Cu" signal "VCC1")
		(22 "In10.Cu" signal "GND4")
		(24 "In11.Cu" signal "IN4")
		(26 "In12.Cu" signal "GND5")
		(28 "In13.Cu" signal "IN5")
		(30 "In14.Cu" signal "GND6")
		(32 "In15.Cu" signal "IN6")
		(34 "In16.Cu" signal "GND7")
		(2 "B.Cu" signal "BOTTOM")
		(9 "F.Adhes" user "F.Adhesive")
		(11 "B.Adhes" user "B.Adhesive")
		(13 "F.Paste" user "Package Geometry/Pastemask Top")
		(15 "B.Paste" user "Package Geometry/Pastemask Bottom")
		(5 "F.SilkS" user "Ref Des/Silkscreen Top")
		(7 "B.SilkS" user "Ref Des/Silkscreen Bottom")
		(1 "F.Mask" user "Board Geometry/Soldermask Top")
		(3 "B.Mask" user "Board Geometry/Soldermask Bottom")
		(17 "Dwgs.User" user "User.Drawings")
		(19 "Cmts.User" user "User.Comments")
		(21 "Eco1.User" user "User.Eco1")
		(23 "Eco2.User" user "User.Eco2")
		(25 "Edge.Cuts" user "Board Geometry/Outline")
		(27 "Margin" user)
		(31 "F.CrtYd" user "Package Geometry/Place Bound Top")
		(29 "B.CrtYd" user "Package Geometry/Place Bound Bottom")
		(35 "F.Fab" user "Ref Des/Assembly Top")
		(33 "B.Fab" user "Ref Des/Assembly Bottom")
	)
	(footprint ""
		(layer "F.Cu")
		(at 67.672458 -27.889962 -90)
		(property "Reference" "PU206"
			(at 4.33959 1.244346 0)
			(unlocked yes)
			(layer "F.SilkS")
			(effects
				(font
					(size 0.7874 0.5842)
					(thickness 0.1524)
				)
				(justify left)
			)
		)
		(property "Value" ""
			(at 0 0 270)
			(layer "F.Fab")
			(effects
				(font
					(size 1.27 1.27)
				)
			)
		)
		(duplicate_pad_numbers_are_jumpers no)
		(pad "1" smd circle
			(at -1.374902 -1.999996 180)
			(size 0 0)
			(layers "F.Cu" "F.Mask" "F.Paste")
			(net "P12V_OCP_V3_2_EN_2_R3")
		)
		(pad "2" smd rect
			(at -1.400048 -1.500124 180)
			(size 0.254 0.8128)
			(layers "F.Cu" "F.Mask" "F.Paste")
			(net "GND")
		)
		(pad "3" smd rect
			(at -1.400048 -0.999998 180)
			(size 0.254 0.8128)
			(layers "F.Cu" "F.Mask" "F.Paste")
			(net "GND")
		)
		(pad "4" smd rect
			(at -1.400048 -0.499872 180)
			(size 0.254 0.8128)
			(layers "F.Cu" "F.Mask" "F.Paste")
			(net "P12V_OCP_TIMER_2")
		)
		(pad "5" smd rect
			(at -1.400048 0 180)
			(size 0.254 0.8128)
			(layers "F.Cu" "F.Mask" "F.Paste")
			(net "P12V_OCP_ISET_2")
		)
		(pad "6" smd rect
			(at -1.400048 0.499872 180)
			(size 0.254 0.8128)
			(layers "F.Cu" "F.Mask" "F.Paste")
			(net "P12V_OCP_SS_2")
		)
		(pad "7" smd rect
			(at -1.400048 0.999998 180)
			(size 0.254 0.8128)
			(layers "F.Cu" "F.Mask" "F.Paste")
			(net "GND")
		)
		(pad "8" smd rect
			(at -1.400048 1.500124 180)
			(size 0.254 0.8128)
			(layers "F.Cu" "F.Mask" "F.Paste")
			(net "P12V_OCP_IMON_2")
		)
		(pad "9" smd rect
			(at -1.400048 1.999996 180)
			(size 0.254 0.8128)
			(layers "F.Cu" "F.Mask" "F.Paste")
			(net "P12V_OCP_FLTB_2")
		)
		(pad "10" smd rect
			(at -0.499872 2.400046 270)
			(size 0.254 0.8128)
			(layers "F.Cu" "F.Mask" "F.Paste")
			(net "HP_LVC3_OCP_V3_2_P12V_PWRGD")
		)
		(pad "11" smd rect
			(at 0.499872 2.400046 270)
			(size 0.254 0.8128)
			(layers "F.Cu" "F.Mask" "F.Paste")
			(net "P12V_OCP_OV_FB_2")
		)
		(pad "12" smd rect
			(at 1.400048 1.999996 180)
			(size 0.254 0.8128)
			(layers "F.Cu" "F.Mask" "F.Paste")
			(net "P12V_OCP_AVIN_PD_2")
		)
		(pad "13" smd rect
			(at 1.400048 1.500124 180)
			(size 0.254 0.8128)
			(layers "F.Cu" "F.Mask" "F.Paste")
			(net "P12V_OCP_V3_2")
		)
		(pad "14" smd rect
			(at 1.400048 0.999998 180)
			(size 0.254 0.8128)
			(layers "F.Cu" "F.Mask" "F.Paste")
			(net "P12V_OCP_V3_2")
		)
		(pad "15" smd rect
			(at 1.400048 0.499872 180)
			(size 0.254 0.8128)
			(layers "F.Cu" "F.Mask" "F.Paste")
			(net "P12V_OCP_V3_2")
		)
		(pad "16" smd rect
			(at 1.400048 0 180)
			(size 0.254 0.8128)
			(layers "F.Cu" "F.Mask" "F.Paste")
			(net "P12V_OCP_V3_2")
		)
		(pad "17" smd rect
			(at 1.400048 -0.499872 180)
			(size 0.254 0.8128)
			(layers "F.Cu" "F.Mask" "F.Paste")
			(net "P12V_OCP_V3_2")
		)
		(pad "18" smd rect
			(at 1.400048 -0.999998 180)
			(size 0.254 0.8128)
			(layers "F.Cu" "F.Mask" "F.Paste")
			(net "P12V_OCP_V3_2")
		)
		(pad "19" smd rect
			(at 1.400048 -1.500124 180)
			(size 0.254 0.8128)
			(layers "F.Cu" "F.Mask" "F.Paste")
			(net "P12V_OCP_V3_2")
		)
		(pad "20" smd rect
			(at 1.400048 -1.999996 180)
			(size 0.254 0.8128)
			(layers "F.Cu" "F.Mask" "F.Paste")
			(net "P12V_OCP_V3_2")
		)
		(pad "21_22" smd circle
			(at 0.499872 -2.337562 180)
			(size 0 0)
			(layers "F.Cu" "F.Mask" "F.Paste")
			(net "P12V_AUX")
		)
		(pad "23" smd rect
			(at 0 -1.100074 180)
			(size 0.254 1.27)
			(layers "F.Cu" "F.Mask" "F.Paste")
			(net "P12V_AUX")
		)
		(pad "24" smd rect
			(at 0 -0.199898 180)
			(size 0.254 1.27)
			(layers "F.Cu" "F.Mask" "F.Paste")
			(net "P12V_AUX")
		)
		(pad "25" smd rect
			(at 0 0.700024 180)
			(size 0.254 1.27)
			(layers "F.Cu" "F.Mask" "F.Paste")
			(net "P12V_AUX")
		)
		(pad "26" smd rect
			(at 0 1.599946 180)
			(size 0.254 1.27)
			(layers "F.Cu" "F.Mask" "F.Paste")
			(net "P12V_AUX")
		)
	)
)
